# 13919-SA_Riser Card_equal length_1120_1.xlsx — PCIE_Storage_IC (si-constraints)
| SPEC |  |  |  |
| Length match | 5 mil |  |  |
| NET | L1 | Length match <1 mil | Length match each other <100 mil |
| P2E_CPU_SAS_RX_DN0 | 739.89 | OK | OK |
| P2E_CPU_SAS_RX_DP0 | 740.3 |  |  |
| P2E_CPU_SAS_RX_DN1 | 735.86 | OK |  |
| P2E_CPU_SAS_RX_DP1 | 734.89 |  |  |
| P2E_CPU_SAS_RX_DN2 | 734.73 | OK |  |
| P2E_CPU_SAS_RX_DP2 | 734.45 |  |  |
| P2E_CPU_SAS_RX_DN3 | 736.52 | OK |  |
| P2E_CPU_SAS_RX_DP3 | 736.26 |  |  |
| P2E_CPU_SAS_RX_DN4 | 734.72 | OK |  |
| P2E_CPU_SAS_RX_DP4 | 734.46 |  |  |
| P2E_CPU_SAS_RX_DN5 | 734.38 | OK |  |
| P2E_CPU_SAS_RX_DP5 | 734.11 |  |  |
| P2E_CPU_SAS_RX_DN6 | 735.45 | OK |  |
| P2E_CPU_SAS_RX_DP6 | 735.2 |  |  |
| P2E_CPU_SAS_RX_DN7 | 736.5 | OK |  |
| P2E_CPU_SAS_RX_DP7 | 736.25 |  |  |
| P2E_CPU_SAS_TX_DN0 | 995.54 | OK | OK |
| P2E_CPU_SAS_TX_DP0 | 995.86 |  |  |
| P2E_CPU_SAS_TX_DN1 | 995.35 | OK |  |
| P2E_CPU_SAS_TX_DP1 | 995.45 |  |  |
| P2E_CPU_SAS_TX_DN2 | 995.94 | OK |  |
| P2E_CPU_SAS_TX_DP2 | 996.1 |  |  |
| P2E_CPU_SAS_TX_DN3 | 990.81 | OK |  |
| P2E_CPU_SAS_TX_DP3 | 991.42 |  |  |
| P2E_CPU_SAS_TX_DN4 | 997.5 | OK |  |
| P2E_CPU_SAS_TX_DP4 | 997.82 |  |  |
| P2E_CPU_SAS_TX_DN5 | 999.06 | OK |  |
| P2E_CPU_SAS_TX_DP5 | 999.2 |  |  |
| P2E_CPU_SAS_TX_DN6 | 993.59 | OK |  |
| P2E_CPU_SAS_TX_DP6 | 993.68 |  |  |
| P2E_CPU_SAS_TX_DN7 | 994.92 | OK |  |
| P2E_CPU_SAS_TX_DP7 | 995.06 |  |  |
